(kicad_pcb
	(version 20260206)
	(generator "pcbnew")
	(generator_version "10.0")
	(general
		(thickness 1.6)
		(legacy_teardrops no)
	)
	(paper "A4")
	(title_block
		(title "04192023_DAF0TMB3IC0_F0TG_MB_C_brd_V02_OCP.brd")
		(comment 1 "Grand Teton / footprints 133-139 of 8354")
	)
	(layers
		(0 "F.Cu" signal "TOP")
		(4 "In1.Cu" signal "GND")
		(6 "In2.Cu" signal "IN1")
		(8 "In3.Cu" signal "GND1")
		(10 "In4.Cu" signal "IN2")
		(12 "In5.Cu" signal "GND2")
		(14 "In6.Cu" signal "IN3")
		(16 "In7.Cu" signal "GND3")
		(18 "In8.Cu" signal "VCC")
		(20 "In9.Cu" signal "VCC1")
		(22 "In10.Cu" signal "GND4")
		(24 "In11.Cu" signal "IN4")
		(26 "In12.Cu" signal "GND5")
		(28 "In13.Cu" signal "IN5")
		(30 "In14.Cu" signal "GND6")
		(32 "In15.Cu" signal "IN6")
		(34 "In16.Cu" signal "GND7")
		(2 "B.Cu" signal "BOTTOM")
		(9 "F.Adhes" user "F.Adhesive")
		(11 "B.Adhes" user "B.Adhesive")
		(13 "F.Paste" user "Package Geometry/Pastemask Top")
		(15 "B.Paste" user "Package Geometry/Pastemask Bottom")
		(5 "F.SilkS" user "Ref Des/Silkscreen Top")
		(7 "B.SilkS" user "Ref Des/Silkscreen Bottom")
		(1 "F.Mask" user "Board Geometry/Soldermask Top")
		(3 "B.Mask" user "Board Geometry/Soldermask Bottom")
		(17 "Dwgs.User" user "User.Drawings")
		(19 "Cmts.User" user "User.Comments")
		(21 "Eco1.User" user "User.Eco1")
		(23 "Eco2.User" user "User.Eco2")
		(25 "Edge.Cuts" user "Board Geometry/Outline")
		(27 "Margin" user)
		(31 "F.CrtYd" user "Package Geometry/Place Bound Top")
		(29 "B.CrtYd" user "Package Geometry/Place Bound Bottom")
		(35 "F.Fab" user "Ref Des/Assembly Top")
		(33 "B.Fab" user "Ref Des/Assembly Bottom")
	)
	(footprint ""
		(layer "F.Cu")
		(at 448.672458 -93.509592 180)
		(property "Reference" "R3617"
			(at 0 0 180)
			(layer "F.SilkS")
			(hide yes)
			(effects
				(font
					(size 1.27 1.27)
				)
			)
		)
		(property "Value" ""
			(at 0 0 180)
			(layer "F.Fab")
			(effects
				(font
					(size 1.27 1.27)
				)
			)
		)
		(duplicate_pad_numbers_are_jumpers no)
		(fp_line
			(start 0.7874 0.4064)
			(end -0.7874 0.4064)
			(stroke
				(width 0.1524)
				(type default)
			)
			(layer "F.SilkS")
		)
		(fp_line
			(start 0.7874 -0.4064)
			(end 0.7874 0.4064)
			(stroke
				(width 0.1524)
				(type default)
			)
			(layer "F.SilkS")
		)
		(fp_line
			(start -0.7874 0.4064)
			(end -0.7874 -0.4064)
			(stroke
				(width 0.1524)
				(type default)
			)
			(layer "F.SilkS")
		)
		(fp_line
			(start -0.7874 -0.4064)
			(end 0.7874 -0.4064)
			(stroke
				(width 0.1524)
				(type default)
			)
			(layer "F.SilkS")
		)
		(fp_line
			(start 0.67945 0.3048)
			(end 0.120396 0.3048)
			(stroke
				(width 0.1)
				(type default)
			)
			(layer "F.Fab")
		)
		(fp_line
			(start 0.67945 -0.3048)
			(end 0.67945 0.3048)
			(stroke
				(width 0.1)
				(type default)
			)
			(layer "F.Fab")
		)
		(fp_line
			(start 0.12065 -0.2794)
			(end 0.12065 -0.3048)
			(stroke
				(width 0.1)
				(type default)
			)
			(layer "F.Fab")
		)
		(fp_line
			(start 0.12065 -0.3048)
			(end 0.67945 -0.3048)
			(stroke
				(width 0.1)
				(type default)
			)
			(layer "F.Fab")
		)
		(fp_line
			(start 0.120396 0.3048)
			(end 0.120396 0.2794)
			(stroke
				(width 0.1)
				(type default)
			)
			(layer "F.Fab")
		)
		(fp_line
			(start 0.120396 0.2794)
			(end -0.12065 0.2794)
			(stroke
				(width 0.1)
				(type default)
			)
			(layer "F.Fab")
		)
		(fp_line
			(start -0.12065 0.3048)
			(end -0.67945 0.3048)
			(stroke
				(width 0.1)
				(type default)
			)
			(layer "F.Fab")
		)
		(fp_line
			(start -0.12065 0.2794)
			(end -0.12065 0.3048)
			(stroke
				(width 0.1)
				(type default)
			)
			(layer "F.Fab")
		)
		(fp_line
			(start -0.12065 -0.2794)
			(end 0.12065 -0.2794)
			(stroke
				(width 0.1)
				(type default)
			)
			(layer "F.Fab")
		)
		(fp_line
			(start -0.12065 -0.305054)
			(end -0.12065 -0.2794)
			(stroke
				(width 0.1)
				(type default)
			)
			(layer "F.Fab")
		)
		(fp_line
			(start -0.67945 0.3048)
			(end -0.67945 -0.305054)
			(stroke
				(width 0.1)
				(type default)
			)
			(layer "F.Fab")
		)
		(fp_line
			(start -0.67945 -0.305054)
			(end -0.12065 -0.305054)
			(stroke
				(width 0.1)
				(type default)
			)
			(layer "F.Fab")
		)
		(pad "1" smd circle
			(at -0.40005 0 180)
			(size 0 0)
			(layers "F.Cu" "F.Mask" "F.Paste")
			(net "GND")
		)
		(pad "2" smd circle
			(at 0.40005 0 180)
			(size 0 0)
			(layers "F.Cu" "F.Mask" "F.Paste")
			(net "INA230_1_A0")
		)
	)
	(footprint ""
		(layer "F.Cu")
		(at 102.268782 -376.982228)
		(property "Reference" "C713"
			(at 0 0 0)
			(layer "F.SilkS")
			(hide yes)
			(effects
				(font
					(size 1.27 1.27)
				)
			)
		)
		(property "Value" ""
			(at 0 0 0)
			(layer "F.Fab")
			(effects
				(font
					(size 1.27 1.27)
				)
			)
		)
		(duplicate_pad_numbers_are_jumpers no)
		(fp_line
			(start -0.299974 -0.150114)
			(end 0.299974 -0.150114)
			(stroke
				(width 0.1)
				(type default)
			)
			(layer "F.Fab")
		)
		(fp_line
			(start -0.299974 0.150114)
			(end -0.299974 -0.150114)
			(stroke
				(width 0.1)
				(type default)
			)
			(layer "F.Fab")
		)
		(fp_line
			(start 0.299974 -0.150114)
			(end 0.299974 0.150114)
			(stroke
				(width 0.1)
				(type default)
			)
			(layer "F.Fab")
		)
		(fp_line
			(start 0.299974 0.150114)
			(end -0.299974 0.150114)
			(stroke
				(width 0.1)
				(type default)
			)
			(layer "F.Fab")
		)
		(pad "1" smd rect
			(at -0.2667 0)
			(size 0.3048 0.381)
			(layers "F.Cu" "F.Mask" "F.Paste")
			(net "P5E_CPU1_P1_TX_C_DP<14>")
		)
		(pad "2" smd rect
			(at 0.2667 0)
			(size 0.3048 0.381)
			(layers "F.Cu" "F.Mask" "F.Paste")
			(net "P5E_CPU1_P1_TX_DP<14>")
		)
	)
	(footprint ""
		(layer "F.Cu")
		(at 178.221894 -353.966272 90)
		(property "Reference" "PR394"
			(at 0 0 90)
			(layer "F.SilkS")
			(hide yes)
			(effects
				(font
					(size 1.27 1.27)
				)
			)
		)
		(property "Value" ""
			(at 0 0 90)
			(layer "F.Fab")
			(effects
				(font
					(size 1.27 1.27)
				)
			)
		)
		(duplicate_pad_numbers_are_jumpers no)
		(fp_line
			(start 0.7874 -0.4064)
			(end 0.7874 0.4064)
			(stroke
				(width 0.1524)
				(type default)
			)
			(layer "F.SilkS")
		)
		(fp_line
			(start -0.7874 -0.4064)
			(end 0.7874 -0.4064)
			(stroke
				(width 0.1524)
				(type default)
			)
			(layer "F.SilkS")
		)
		(fp_line
			(start 0.7874 0.4064)
			(end -0.7874 0.4064)
			(stroke
				(width 0.1524)
				(type default)
			)
			(layer "F.SilkS")
		)
		(fp_line
			(start -0.7874 0.4064)
			(end -0.7874 -0.4064)
			(stroke
				(width 0.1524)
				(type default)
			)
			(layer "F.SilkS")
		)
		(fp_line
			(start -0.12065 -0.305054)
			(end -0.12065 -0.2794)
			(stroke
				(width 0.1)
				(type default)
			)
			(layer "F.Fab")
		)
		(fp_line
			(start -0.67945 -0.305054)
			(end -0.12065 -0.305054)
			(stroke
				(width 0.1)
				(type default)
			)
			(layer "F.Fab")
		)
		(fp_line
			(start 0.67945 -0.3048)
			(end 0.67945 0.3048)
			(stroke
				(width 0.1)
				(type default)
			)
			(layer "F.Fab")
		)
		(fp_line
			(start 0.12065 -0.3048)
			(end 0.67945 -0.3048)
			(stroke
				(width 0.1)
				(type default)
			)
			(layer "F.Fab")
		)
		(fp_line
			(start 0.12065 -0.2794)
			(end 0.12065 -0.3048)
			(stroke
				(width 0.1)
				(type default)
			)
			(layer "F.Fab")
		)
		(fp_line
			(start -0.12065 -0.2794)
			(end 0.12065 -0.2794)
			(stroke
				(width 0.1)
				(type default)
			)
			(layer "F.Fab")
		)
		(fp_line
			(start 0.120396 0.2794)
			(end -0.12065 0.2794)
			(stroke
				(width 0.1)
				(type default)
			)
			(layer "F.Fab")
		)
		(fp_line
			(start -0.12065 0.2794)
			(end -0.12065 0.3048)
			(stroke
				(width 0.1)
				(type default)
			)
			(layer "F.Fab")
		)
		(fp_line
			(start 0.67945 0.3048)
			(end 0.120396 0.3048)
			(stroke
				(width 0.1)
				(type default)
			)
			(layer "F.Fab")
		)
		(fp_line
			(start 0.120396 0.3048)
			(end 0.120396 0.2794)
			(stroke
				(width 0.1)
				(type default)
			)
			(layer "F.Fab")
		)
		(fp_line
			(start -0.12065 0.3048)
			(end -0.67945 0.3048)
			(stroke
				(width 0.1)
				(type default)
			)
			(layer "F.Fab")
		)
		(fp_line
			(start -0.67945 0.3048)
			(end -0.67945 -0.305054)
			(stroke
				(width 0.1)
				(type default)
			)
			(layer "F.Fab")
		)
		(pad "1" smd circle
			(at -0.40005 0 90)
			(size 0 0)
			(layers "F.Cu" "F.Mask" "F.Paste")
			(net "PVDD11_S3_P1_PVCC")
		)
		(pad "2" smd circle
			(at 0.40005 0 90)
			(size 0 0)
			(layers "F.Cu" "F.Mask" "F.Paste")
			(net "P3V3_AUX")
		)
	)
	(footprint ""
		(layer "F.Cu")
		(at 27.487626 -427.612302 180)
		(property "Reference" "R6159"
			(at 0 0 180)
			(layer "F.SilkS")
			(hide yes)
			(effects
				(font
					(size 1.27 1.27)
				)
			)
		)
		(property "Value" ""
			(at 0 0 180)
			(layer "F.Fab")
			(effects
				(font
					(size 1.27 1.27)
				)
			)
		)
		(duplicate_pad_numbers_are_jumpers no)
		(fp_line
			(start 0.32512 0.175006)
			(end -0.32512 0.175006)
			(stroke
				(width 0.1)
				(type default)
			)
			(layer "F.Fab")
		)
		(fp_line
			(start 0.32512 -0.175006)
			(end 0.32512 0.175006)
			(stroke
				(width 0.1)
				(type default)
			)
			(layer "F.Fab")
		)
		(fp_line
			(start -0.32512 0.175006)
			(end -0.32512 -0.175006)
			(stroke
				(width 0.1)
				(type default)
			)
			(layer "F.Fab")
		)
		(fp_line
			(start -0.32512 -0.175006)
			(end 0.32512 -0.175006)
			(stroke
				(width 0.1)
				(type default)
			)
			(layer "F.Fab")
		)
		(pad "1" smd rect
			(at -0.2667 0 180)
			(size 0.3048 0.381)
			(layers "F.Cu" "F.Mask" "F.Paste")
			(net "P2E_MB_BMC_RX_DN<0>")
		)
		(pad "2" smd rect
			(at 0.2667 0)
			(size 0.3048 0.381)
			(layers "F.Cu" "F.Mask" "F.Paste")
			(net "P2E_MB_BMC_RX_R2_DN<0>")
		)
	)
	(footprint ""
		(layer "F.Cu")
		(at 277.591774 -414.00603)
		(property "Reference" "R6782"
			(at 0 0 0)
			(layer "F.SilkS")
			(hide yes)
			(effects
				(font
					(size 1.27 1.27)
				)
			)
		)
		(property "Value" ""
			(at 0 0 0)
			(layer "F.Fab")
			(effects
				(font
					(size 1.27 1.27)
				)
			)
		)
		(duplicate_pad_numbers_are_jumpers no)
		(fp_line
			(start -0.7874 -0.4064)
			(end 0.7874 -0.4064)
			(stroke
				(width 0.1524)
				(type default)
			)
			(layer "F.SilkS")
		)
		(fp_line
			(start -0.7874 0.4064)
			(end -0.7874 -0.4064)
			(stroke
				(width 0.1524)
				(type default)
			)
			(layer "F.SilkS")
		)
		(fp_line
			(start 0.7874 -0.4064)
			(end 0.7874 0.4064)
			(stroke
				(width 0.1524)
				(type default)
			)
			(layer "F.SilkS")
		)
		(fp_line
			(start 0.7874 0.4064)
			(end -0.7874 0.4064)
			(stroke
				(width 0.1524)
				(type default)
			)
			(layer "F.SilkS")
		)
		(fp_line
			(start -0.67945 -0.305054)
			(end -0.12065 -0.305054)
			(stroke
				(width 0.1)
				(type default)
			)
			(layer "F.Fab")
		)
		(fp_line
			(start -0.67945 0.3048)
			(end -0.67945 -0.305054)
			(stroke
				(width 0.1)
				(type default)
			)
			(layer "F.Fab")
		)
		(fp_line
			(start -0.12065 -0.305054)
			(end -0.12065 -0.2794)
			(stroke
				(width 0.1)
				(type default)
			)
			(layer "F.Fab")
		)
		(fp_line
			(start -0.12065 -0.2794)
			(end 0.12065 -0.2794)
			(stroke
				(width 0.1)
				(type default)
			)
			(layer "F.Fab")
		)
		(fp_line
			(start -0.12065 0.2794)
			(end -0.12065 0.3048)
			(stroke
				(width 0.1)
				(type default)
			)
			(layer "F.Fab")
		)
		(fp_line
			(start -0.12065 0.3048)
			(end -0.67945 0.3048)
			(stroke
				(width 0.1)
				(type default)
			)
			(layer "F.Fab")
		)
		(fp_line
			(start 0.120396 0.2794)
			(end -0.12065 0.2794)
			(stroke
				(width 0.1)
				(type default)
			)
			(layer "F.Fab")
		)
		(fp_line
			(start 0.120396 0.3048)
			(end 0.120396 0.2794)
			(stroke
				(width 0.1)
				(type default)
			)
			(layer "F.Fab")
		)
		(fp_line
			(start 0.12065 -0.3048)
			(end 0.67945 -0.3048)
			(stroke
				(width 0.1)
				(type default)
			)
			(layer "F.Fab")
		)
		(fp_line
			(start 0.12065 -0.2794)
			(end 0.12065 -0.3048)
			(stroke
				(width 0.1)
				(type default)
			)
			(layer "F.Fab")
		)
		(fp_line
			(start 0.67945 -0.3048)
			(end 0.67945 0.3048)
			(stroke
				(width 0.1)
				(type default)
			)
			(layer "F.Fab")
		)
		(fp_line
			(start 0.67945 0.3048)
			(end 0.120396 0.3048)
			(stroke
				(width 0.1)
				(type default)
			)
			(layer "F.Fab")
		)
		(pad "1" smd circle
			(at -0.40005 0)
			(size 0 0)
			(layers "F.Cu" "F.Mask" "F.Paste")
			(net "SMB_MUX_RT_ROM_R1_SCL")
		)
		(pad "2" smd circle
			(at 0.40005 0)
			(size 0 0)
			(layers "F.Cu" "F.Mask" "F.Paste")
			(net "SMB_HOST_CLK_3V3AUX_SCL_R1")
		)
	)
	(footprint ""
		(layer "F.Cu")
		(at 374.131586 -426.567854 -90)
		(property "Reference" "U46"
			(at -3.060192 -0.117602 0)
			(unlocked yes)
			(layer "F.SilkS")
			(effects
				(font
					(size 0.7874 0.5842)
					(thickness 0.1524)
				)
			)
		)
		(property "Value" ""
			(at 0 0 270)
			(layer "F.Fab")
			(effects
				(font
					(size 1.27 1.27)
				)
			)
		)
		(duplicate_pad_numbers_are_jumpers no)
		(fp_line
			(start -1.03378 1.284478)
			(end -1.03378 -1.284478)
			(stroke
				(width 0.1524)
				(type default)
			)
			(layer "F.SilkS")
		)
		(fp_line
			(start 1.03378 1.284478)
			(end -1.03378 1.284478)
			(stroke
				(width 0.1524)
				(type default)
			)
			(layer "F.SilkS")
		)
		(fp_line
			(start -1.03378 -1.284478)
			(end 1.03378 -1.284478)
			(stroke
				(width 0.1524)
				(type default)
			)
			(layer "F.SilkS")
		)
		(fp_line
			(start 1.03378 -1.284478)
			(end 1.03378 1.284478)
			(stroke
				(width 0.1524)
				(type default)
			)
			(layer "F.SilkS")
		)
		(fp_poly
			(pts
				(xy -1.201674 -0.750062) (xy -1.806702 -0.447548) (xy -1.806702 -1.052576)
			)
			(stroke
				(width 0)
				(type default)
			)
			(fill yes)
			(layer "F.SilkS")
		)
		(fp_line
			(start -0.774954 1.02489)
			(end -0.774954 -1.02489)
			(stroke
				(width 0.1)
				(type default)
			)
			(layer "F.Fab")
		)
		(fp_line
			(start 0.774954 1.02489)
			(end -0.774954 1.02489)
			(stroke
				(width 0.1)
				(type default)
			)
			(layer "F.Fab")
		)
		(fp_line
			(start -0.774954 -1.02489)
			(end 0.774954 -1.02489)
			(stroke
				(width 0.1)
				(type default)
			)
			(layer "F.Fab")
		)
		(fp_line
			(start 0.774954 -1.02489)
			(end 0.774954 1.02489)
			(stroke
				(width 0.1)
				(type default)
			)
			(layer "F.Fab")
		)
		(fp_poly
			(pts
				(xy -1.201674 -0.750062) (xy -1.806702 -0.447548) (xy -1.806702 -1.052576)
			)
			(stroke
				(width 0)
				(type default)
			)
			(fill yes)
			(layer "F.Fab")
		)
		(pad "1" smd rect
			(at -0.64008 -0.750062)
			(size 0.3048 0.5334)
			(layers "F.Cu" "F.Mask" "F.Paste")
			(net "SMB_RT_CPU0_P3_ROM_MUX_1D_SCL")
		)
		(pad "2" smd rect
			(at -0.64008 -0.249936)
			(size 0.254 0.5334)
			(layers "F.Cu" "F.Mask" "F.Paste")
			(net "SMB_RT_CPU0_P3_ROM_MUX_1D_SDA")
		)
		(pad "3" smd rect
			(at -0.64008 0.249936)
			(size 0.254 0.5334)
			(layers "F.Cu" "F.Mask" "F.Paste")
			(net "SMB_RT_CPU0_P3_ROM_MUX_2D_SCL")
		)
		(pad "4" smd rect
			(at -0.64008 0.750062)
			(size 0.3048 0.5334)
			(layers "F.Cu" "F.Mask" "F.Paste")
			(net "SMB_RT_CPU0_P3_ROM_MUX_2D_SDA")
		)
		(pad "5" smd rect
			(at 0 0.839978 270)
			(size 0.3302 0.635)
			(layers "F.Cu" "F.Mask" "F.Paste")
			(net "GND")
		)
		(pad "6" smd rect
			(at 0.64008 0.750062)
			(size 0.3048 0.5334)
			(layers "F.Cu" "F.Mask" "F.Paste")
			(net "RT_ROM_MUX7_OE_N")
		)
		(pad "7" smd rect
			(at 0.64008 0.249936)
			(size 0.254 0.5334)
			(layers "F.Cu" "F.Mask" "F.Paste")
			(net "SMB_RT_CPU0_P3_ROM_R_SDA")
		)
		(pad "8" smd rect
			(at 0.64008 -0.249936)
			(size 0.254 0.5334)
			(layers "F.Cu" "F.Mask" "F.Paste")
			(net "SMB_RT_CPU0_P3_ROM_R_SCL")
		)
		(pad "9" smd rect
			(at 0.64008 -0.750062)
			(size 0.3048 0.5334)
			(layers "F.Cu" "F.Mask" "F.Paste")
			(net "FM_SMB_RT_ROM_MUX7_SEL")
		)
		(pad "10" smd rect
			(at 0 -0.839978 270)
			(size 0.3302 0.635)
			(layers "F.Cu" "F.Mask" "F.Paste")
			(net "P3V3_AUX")
		)
	)
	(footprint ""
		(layer "F.Cu")
		(at 368.955066 -424.002962 90)
		(property "Reference" "R4199"
			(at 0 0 90)
			(layer "F.SilkS")
			(hide yes)
			(effects
				(font
					(size 1.27 1.27)
				)
			)
		)
		(property "Value" ""
			(at 0 0 90)
			(layer "F.Fab")
			(effects
				(font
					(size 1.27 1.27)
				)
			)
		)
		(duplicate_pad_numbers_are_jumpers no)
		(fp_line
			(start 0.7874 -0.4064)
			(end 0.7874 0.4064)
			(stroke
				(width 0.1524)
				(type default)
			)
			(layer "F.SilkS")
		)
		(fp_line
			(start -0.7874 -0.4064)
			(end 0.7874 -0.4064)
			(stroke
				(width 0.1524)
				(type default)
			)
			(layer "F.SilkS")
		)
		(fp_line
			(start 0.7874 0.4064)
			(end -0.7874 0.4064)
			(stroke
				(width 0.1524)
				(type default)
			)
			(layer "F.SilkS")
		)
		(fp_line
			(start -0.7874 0.4064)
			(end -0.7874 -0.4064)
			(stroke
				(width 0.1524)
				(type default)
			)
			(layer "F.SilkS")
		)
		(fp_line
			(start -0.12065 -0.305054)
			(end -0.12065 -0.2794)
			(stroke
				(width 0.1)
				(type default)
			)
			(layer "F.Fab")
		)
		(fp_line
			(start -0.67945 -0.305054)
			(end -0.12065 -0.305054)
			(stroke
				(width 0.1)
				(type default)
			)
			(layer "F.Fab")
		)
		(fp_line
			(start 0.67945 -0.3048)
			(end 0.67945 0.3048)
			(stroke
				(width 0.1)
				(type default)
			)
			(layer "F.Fab")
		)
		(fp_line
			(start 0.12065 -0.3048)
			(end 0.67945 -0.3048)
			(stroke
				(width 0.1)
				(type default)
			)
			(layer "F.Fab")
		)
		(fp_line
			(start 0.12065 -0.2794)
			(end 0.12065 -0.3048)
			(stroke
				(width 0.1)
				(type default)
			)
			(layer "F.Fab")
		)
		(fp_line
			(start -0.12065 -0.2794)
			(end 0.12065 -0.2794)
			(stroke
				(width 0.1)
				(type default)
			)
			(layer "F.Fab")
		)
		(fp_line
			(start 0.120396 0.2794)
			(end -0.12065 0.2794)
			(stroke
				(width 0.1)
				(type default)
			)
			(layer "F.Fab")
		)
		(fp_line
			(start -0.12065 0.2794)
			(end -0.12065 0.3048)
			(stroke
				(width 0.1)
				(type default)
			)
			(layer "F.Fab")
		)
		(fp_line
			(start 0.67945 0.3048)
			(end 0.120396 0.3048)
			(stroke
				(width 0.1)
				(type default)
			)
			(layer "F.Fab")
		)
		(fp_line
			(start 0.120396 0.3048)
			(end 0.120396 0.2794)
			(stroke
				(width 0.1)
				(type default)
			)
			(layer "F.Fab")
		)
		(fp_line
			(start -0.12065 0.3048)
			(end -0.67945 0.3048)
			(stroke
				(width 0.1)
				(type default)
			)
			(layer "F.Fab")
		)
		(fp_line
			(start -0.67945 0.3048)
			(end -0.67945 -0.305054)
			(stroke
				(width 0.1)
				(type default)
			)
			(layer "F.Fab")
		)
		(pad "1" smd circle
			(at -0.40005 0 90)
			(size 0 0)
			(layers "F.Cu" "F.Mask" "F.Paste")
			(net "U270_0_ADD1")
		)
		(pad "2" smd circle
			(at 0.40005 0 90)
			(size 0 0)
			(layers "F.Cu" "F.Mask" "F.Paste")
			(net "GND")
		)
	)
)
